# T6G (Grand Teton) — schematic parts with pin connectivity, parts 8082–8082 of 8303; source: Cadence DE-HDL packaged netlist (pstxprt.dat, pstxnet.dat, pstchip.dat)

U26  GENOA_SP5  SOCKET6096_13568-001 IO  pkg SOCKET6096_93-4X120-45XA  page 37  (pins 4033-4368 of 6096)
  CV8  VSS_CV8  POWER  = GND
  CV9  MLB_DATA20  BI  = M_L_CPU1_SB_DQ<20>
  CV10  VSS_CV10  POWER  = GND
  CV11  MLB_DQS_H7  BI  = M_L_CPU1_SB_DQS_DP<7>
  CV12  VSS_CV12  POWER  = GND
  CV13  MHB_DATA20  BI  = M_H_CPU1_SB_DQ<20>
  CV14  MHB_DQS_H7  BI  = M_H_CPU1_SB_DQS_DP<7>
  CV15  VSS_CV15  POWER  = GND
  CV16  MJB_DATA20  BI  = M_J_CPU1_SB_DQ<20>
  CV17  VSS_CV17  POWER  = GND
  CV18  MJB_DQS_H7  BI  = M_J_CPU1_SB_DQS_DP<7>
  CV19  VSS_CV19  POWER  = GND
  CV20  MIB_DATA20  BI  = M_I_CPU1_SB_DQ<20>
  CV21  MIB_DQS_H7  BI  = M_I_CPU1_SB_DQS_DP<7>
  CV22  VSS_CV22  POWER  = GND
  CV23  VDDCR_CPU1_CV23  POWER  = PVDDCR_CPU1_P1
  CV24  VDDCR_CPU1_CV24  POWER  = PVDDCR_CPU1_P1
  CV25  VSS_CV25  POWER  = GND
  CV26  VDDCR_CPU1_CV26  POWER  = PVDDCR_CPU1_P1
  CV27  VDDCR_CPU1_CV27  POWER  = PVDDCR_CPU1_P1
  CV28  VSS_CV28  POWER  = GND
  CV29  VDDCR_CPU1_CV29  POWER  = PVDDCR_CPU1_P1
  CV30  VDDCR_CPU1_CV30  POWER  = PVDDCR_CPU1_P1
  CV31  VSS_CV31  POWER  = GND
  CV32  VDDCR_CPU1_CV32  POWER  = PVDDCR_CPU1_P1
  CV33  VDDCR_CPU1_CV33  POWER  = PVDDCR_CPU1_P1
  CV34  VSS_CV34  POWER  = GND
  CV35  P3_RXP0  IN  = P5E_CPU1_P3_RX_DP<0>
  CV36  P3_RXN0  IN  = P5E_CPU1_P3_RX_DN<0>
  CV37  VSS_CV37  POWER  = GND
  CV39  VSS_CV39  POWER  = GND
  CV40  P1_TXN15  OUT  = P5E_CPU1_P1_TX_DN<15>
  CV41  P1_TXP15  OUT  = P5E_CPU1_P1_TX_DP<15>
  CV42  VSS_CV42  POWER  = GND
  CV43  VDDCR_CPU1_CV43  POWER  = PVDDCR_CPU1_P1
  CV44  VDDCR_CPU1_CV44  POWER  = PVDDCR_CPU1_P1
  CV45  VSS_CV45  POWER  = GND
  CV46  VDDCR_CPU1_CV46  POWER  = PVDDCR_CPU1_P1
  CV47  VDDCR_CPU1_CV47  POWER  = PVDDCR_CPU1_P1
  CV48  VSS_CV48  POWER  = GND
  CV49  VDDCR_CPU1_CV49  POWER  = PVDDCR_CPU1_P1
  CV50  VDDCR_CPU1_CV50  POWER  = PVDDCR_CPU1_P1
  CV51  VSS_CV51  POWER  = GND
  CV52  VDDCR_CPU1_CV52  POWER  = PVDDCR_CPU1_P1
  CV53  VDDCR_CPU1_CV53  POWER  = PVDDCR_CPU1_P1
  CV54  VSS_CV54  POWER  = GND
  CV55  MCB_DQS_H7  BI  = M_C_CPU1_SB_DQS_DP<7>
  CV56  MCB_DATA20  BI  = M_C_CPU1_SB_DQ<20>
  CV57  VSS_CV57  POWER  = GND
  CV58  MDB_DQS_H7  BI  = M_D_CPU1_SB_DQS_DP<7>
  CV59  VSS_CV59  POWER  = GND
  CV60  MDB_DATA20  BI  = M_D_CPU1_SB_DQ<20>
  CV61  VSS_CV61  POWER  = GND
  CV62  MBB_DQS_H7  BI  = M_B_CPU1_SB_DQS_DP<7>
  CV63  MBB_DATA20  BI  = M_B_CPU1_SB_DQ<20>
  CV64  VSS_CV64  POWER  = GND
  CV65  MFB_DQS_H7  BI  = M_F_CPU1_SB_DQS_DP<7>
  CV66  VSS_CV66  POWER  = GND
  CV67  MFB_DATA20  BI  = M_F_CPU1_SB_DQ<20>
  CV68  VSS_CV68  POWER  = GND
  CV69  MEB_DQS_H7  BI  = M_E_CPU1_SB_DQS_DP<7>
  CV70  MEB_DATA20  BI  = M_E_CPU1_SB_DQ<20>
  CV71  VSS_CV71  POWER  = GND
  CV72  MAB_DQS_H7  BI  = M_A_CPU1_SB_DQS_DP<7>
  CV73  VSS_CV73  POWER  = GND
  CV74  MAB_DATA20  BI  = M_A_CPU1_SB_DQ<20>
  CW1  VSS_CW1  POWER  = GND
  CW2  MGB_DATA22  BI  = M_G_CPU1_SB_DQ<22>
  CW3  MGB_DATA21  BI  = M_G_CPU1_SB_DQ<21>
  CW4  VDD_11_S3_CW4  POWER  = PVDD11_S3_P1
  CW5  MKB_DATA22  BI  = M_K_CPU1_SB_DQ<22>
  CW6  VSS_CW6  POWER  = GND
  CW7  MKB_DATA21  BI  = M_K_CPU1_SB_DQ<21>
  CW8  VSS_CW8  POWER  = GND
  CW9  MLB_DATA22  BI  = M_L_CPU1_SB_DQ<22>
  CW10  MLB_DATA21  BI  = M_L_CPU1_SB_DQ<21>
  CW11  VDD_11_S3_CW11  POWER  = PVDD11_S3_P1
  CW12  MHB_DATA22  BI  = M_H_CPU1_SB_DQ<22>
  CW13  VSS_CW13  POWER  = GND
  CW14  MHB_DATA21  BI  = M_H_CPU1_SB_DQ<21>
  CW15  VSS_CW15  POWER  = GND
  CW16  MJB_DATA22  BI  = M_J_CPU1_SB_DQ<22>
  CW17  MJB_DATA21  BI  = M_J_CPU1_SB_DQ<21>
  CW18  VDD_11_S3_CW18  POWER  = PVDD11_S3_P1
  CW19  MIB_DATA22  BI  = M_I_CPU1_SB_DQ<22>
  CW20  VSS_CW20  POWER  = GND
  CW21  MIB_DATA21  BI  = M_I_CPU1_SB_DQ<21>
  CW22  VSS_CW22  POWER  = GND
  CW23  P3_RXP12  IN  = P5E_CPU1_P3_RX_DP<12>
  CW24  P3_RXN12  IN  = P5E_CPU1_P3_RX_DN<12>
  CW25  VSS_CW25  POWER  = GND
  CW26  P3_RXP9  IN  = P5E_CPU1_P3_RX_DP<9>
  CW27  P3_RXN9  IN  = P5E_CPU1_P3_RX_DN<9>
  CW28  VSS_CW28  POWER  = GND
  CW29  P3_RXP6  IN  = P5E_CPU1_P3_RX_DP<6>
  CW30  P3_RXN6  IN  = P5E_CPU1_P3_RX_DN<6>
  CW31  VSS_CW31  POWER  = GND
  CW32  P3_RXP3  IN  = P5E_CPU1_P3_RX_DP<3>
  CW33  P3_RXN3  IN  = P5E_CPU1_P3_RX_DN<3>
  CW34  VSS_CW34  POWER  = GND
  CW35  VSS_CW35  POWER  = GND
  CW36  VSS_CW36  POWER  = GND
  CW40  VSS_CW40  POWER  = GND
  CW41  VSS_CW41  POWER  = GND
  CW42  VSS_CW42  POWER  = GND
  CW43  P1_TXN12  OUT  = P5E_CPU1_P1_TX_DN<12>
  CW44  P1_TXP12  OUT  = P5E_CPU1_P1_TX_DP<12>
  CW45  VSS_CW45  POWER  = GND
  CW46  P1_TXN9  OUT  = P5E_CPU1_P1_TX_DN<9>
  CW47  P1_TXP9  OUT  = P5E_CPU1_P1_TX_DP<9>
  CW48  VSS_CW48  POWER  = GND
  CW49  P1_TXN6  OUT  = P5E_CPU1_P1_TX_DN<6>
  CW50  P1_TXP6  OUT  = P5E_CPU1_P1_TX_DP<6>
  CW51  VSS_CW51  POWER  = GND
  CW52  P1_TXN3  OUT  = P5E_CPU1_P1_TX_DN<3>
  CW53  P1_TXP3  OUT  = P5E_CPU1_P1_TX_DP<3>
  CW54  VSS_CW54  POWER  = GND
  CW55  MCB_DATA21  BI  = M_C_CPU1_SB_DQ<21>
  CW56  VSS_CW56  POWER  = GND
  CW57  MCB_DATA22  BI  = M_C_CPU1_SB_DQ<22>
  CW58  VDDIO_CW58  POWER  = PVDDIO_P1
  CW59  MDB_DATA21  BI  = M_D_CPU1_SB_DQ<21>
  CW60  MDB_DATA22  BI  = M_D_CPU1_SB_DQ<22>
  CW61  VSS_CW61  POWER  = GND
  CW62  MBB_DATA21  BI  = M_B_CPU1_SB_DQ<21>
  CW63  VSS_CW63  POWER  = GND
  CW64  MBB_DATA22  BI  = M_B_CPU1_SB_DQ<22>
  CW65  VDDIO_CW65  POWER  = PVDDIO_P1
  CW66  MFB_DATA21  BI  = M_F_CPU1_SB_DQ<21>
  CW67  MFB_DATA22  BI  = M_F_CPU1_SB_DQ<22>
  CW68  VSS_CW68  POWER  = GND
  CW69  MEB_DATA21  BI  = M_E_CPU1_SB_DQ<21>
  CW70  VSS_CW70  POWER  = GND
  CW71  MEB_DATA22  BI  = M_E_CPU1_SB_DQ<22>
  CW72  VDDIO_CW72  POWER  = PVDDIO_P1
  CW73  MAB_DATA21  BI  = M_A_CPU1_SB_DQ<21>
  CW74  MAB_DATA22  BI  = M_A_CPU1_SB_DQ<22>
  CW75  VSS_CW75  POWER  = GND
  CY2  MGB_DATA24  BI  = M_G_CPU1_SB_DQ<24>
  CY3  VSS_CY3  POWER  = GND
  CY4  MGB_DATA23  BI  = M_G_CPU1_SB_DQ<23>
  CY5  VSS_CY5  POWER  = GND
  CY6  MKB_DATA24  BI  = M_K_CPU1_SB_DQ<24>
  CY7  MKB_DATA23  BI  = M_K_CPU1_SB_DQ<23>
  CY8  VSS_CY8  POWER  = GND
  CY9  MLB_DATA24  BI  = M_L_CPU1_SB_DQ<24>
  CY10  VSS_CY10  POWER  = GND
  CY11  MLB_DATA23  BI  = M_L_CPU1_SB_DQ<23>
  CY12  VSS_CY12  POWER  = GND
  CY13  MHB_DATA24  BI  = M_H_CPU1_SB_DQ<24>
  CY14  MHB_DATA23  BI  = M_H_CPU1_SB_DQ<23>
  CY15  VSS_CY15  POWER  = GND
  CY16  MJB_DATA24  BI  = M_J_CPU1_SB_DQ<24>
  CY17  VSS_CY17  POWER  = GND
  CY18  MJB_DATA23  BI  = M_J_CPU1_SB_DQ<23>
  CY19  VSS_CY19  POWER  = GND
  CY20  MIB_DATA24  BI  = M_I_CPU1_SB_DQ<24>
  CY21  MIB_DATA23  BI  = M_I_CPU1_SB_DQ<23>
  CY22  VDD_11_S3_CY22  POWER  = PVDD11_S3_P1
  CY23  VSS_CY23  POWER  = GND
  CY24  VSS_CY24  POWER  = GND
  CY25  VSS_CY25  POWER  = GND
  CY26  VSS_CY26  POWER  = GND
  CY27  VSS_CY27  POWER  = GND
  CY28  VSS_CY28  POWER  = GND
  CY29  VSS_CY29  POWER  = GND
  CY30  VSS_CY30  POWER  = GND
  CY31  VSS_CY31  POWER  = GND
  CY32  VSS_CY32  POWER  = GND
  CY33  VSS_CY33  POWER  = GND
  CY34  VSS_CY34  POWER  = GND
  CY35  P3_RXP1  IN  = P5E_CPU1_P3_RX_DP<1>
  CY36  P3_RXN1  IN  = P5E_CPU1_P3_RX_DN<1>
  CY37  VSS_CY37  POWER  = GND
  CY39  VSS_CY39  POWER  = GND
  CY40  P1_TXN14  OUT  = P5E_CPU1_P1_TX_DN<14>
  CY41  P1_TXP14  OUT  = P5E_CPU1_P1_TX_DP<14>
  CY42  VSS_CY42  POWER  = GND
  CY43  VSS_CY43  POWER  = GND
  CY44  VSS_CY44  POWER  = GND
  CY45  VSS_CY45  POWER  = GND
  CY46  VSS_CY46  POWER  = GND
  CY47  VSS_CY47  POWER  = GND
  CY48  VSS_CY48  POWER  = GND
  CY49  VSS_CY49  POWER  = GND
  CY50  VSS_CY50  POWER  = GND
  CY51  VSS_CY51  POWER  = GND
  CY52  VSS_CY52  POWER  = GND
  CY53  VSS_CY53  POWER  = GND
  CY54  VDDIO_CY54  POWER  = PVDDIO_P1
  CY55  MCB_DATA23  BI  = M_C_CPU1_SB_DQ<23>
  CY56  MCB_DATA24  BI  = M_C_CPU1_SB_DQ<24>
  CY57  VSS_CY57  POWER  = GND
  CY58  MDB_DATA23  BI  = M_D_CPU1_SB_DQ<23>
  CY59  VSS_CY59  POWER  = GND
  CY60  MDB_DATA24  BI  = M_D_CPU1_SB_DQ<24>
  CY61  VSS_CY61  POWER  = GND
  CY62  MBB_DATA23  BI  = M_B_CPU1_SB_DQ<23>
  CY63  MBB_DATA24  BI  = M_B_CPU1_SB_DQ<24>
  CY64  VSS_CY64  POWER  = GND
  CY65  MFB_DATA23  BI  = M_F_CPU1_SB_DQ<23>
  CY66  VSS_CY66  POWER  = GND
  CY67  MFB_DATA24  BI  = M_F_CPU1_SB_DQ<24>
  CY68  VSS_CY68  POWER  = GND
  CY69  MEB_DATA23  BI  = M_E_CPU1_SB_DQ<23>
  CY70  MEB_DATA24  BI  = M_E_CPU1_SB_DQ<24>
  CY71  VSS_CY71  POWER  = GND
  CY72  MAB_DATA23  BI  = M_A_CPU1_SB_DQ<23>
  CY73  VSS_CY73  POWER  = GND
  CY74  MAB_DATA24  BI  = M_A_CPU1_SB_DQ<24>
  D2  VSS_D2  POWER  = GND
  D3  VSS_D3  POWER  = GND
  D4  RSVD_D4  TRI  = NC
  D5  VSS_D5  POWER  = GND
  D6  VSS_D6  POWER  = GND
  D7  TEST47_IOD1  TRI  = TP_CPU1_TEST47_IOD1
  D8  RSVD_D8  TRI  = NC
  D9  VSS_D9  POWER  = GND
  D10  VSS_D10  POWER  = GND
  D11  RSVD_D11  TRI  = NC
  D12  VSS_D12  POWER  = GND
  D13  VSS_D13  POWER  = GND
  D14  \sec_sda||agpio263\  BI  = SMB_CPU1_SEC_SDA
  D15  \sgpio_dataout||agpio260\  BI  = NC
  D16  VSS_D16  POWER  = GND
  D17  VSS_D17  POWER  = GND
  D18  \pcie_rst0_l||agpio266\  BI  = RST_CPU1_PERST0_N
  D19  VSS_D19  POWER  = GND
  D20  VSS_D20  POWER  = GND
  D21  VSS_D21  POWER  = GND
  D22  RSVD_D22  TRI  = NC
  D23  TEST5_CCD15  TRI  = NC
  D24  VSS_D24  POWER  = GND
  D25  VSS_D25  POWER  = GND
  D26  VSS_D26  POWER  = GND
  D27  VSS_D27  POWER  = GND
  D28  VSS_D28  POWER  = GND
  D29  VSS_D29  POWER  = GND
  D30  VSS_D30  POWER  = GND
  D31  VSS_D31  POWER  = GND
  D32  AZ_SYNC  OUT  = NC_CPU1_AZ_SYNC
  D33  \az_sdin1||sw_mclk\  OUT  = NC_CPU1_AZ_SDIN1
  D34  RSVD_D34  TRI  = NC
  D35  VSS_D35  POWER  = GND
  D36  RSVD_D36  TRI  = NC
  D37  VSS_D37  POWER  = GND
  D39  VSS_D39  POWER  = GND
  D40  VSS_D40  POWER  = GND
  D41  VSS_D41  POWER  = GND
  D42  VSS_D42  POWER  = GND
  D43  VSS_D43  POWER  = GND
  D44  VSS_D44  POWER  = GND
  D45  VSS_D45  POWER  = GND
  D46  VSS_D46  POWER  = GND
  D47  VSS_D47  POWER  = GND
  D48  VSS_D48  POWER  = GND
  D49  VSS_D49  POWER  = GND
  D50  VSS_D50  POWER  = GND
  D51  VSS_D51  POWER  = GND
  D52  VSS_D52  POWER  = GND
  D53  VSS_D53  POWER  = GND
  D54  VSS_D54  POWER  = GND
  D55  VDDCR_CPU0_D55  POWER  = PVDDCR_CPU0_P1
  D56  VDDCR_CPU0_D56  POWER  = PVDDCR_CPU0_P1
  D57  VSS_D57  POWER  = GND
  D58  RSVD_D58  TRI  = NC
  D59  VSS_D59  POWER  = GND
  D60  VSS_D60  POWER  = GND
  D61  VSS_D61  POWER  = GND
  D62  RSVD_D62  TRI  = NC
  D63  VSS_D63  POWER  = GND
  D64  VSS_D64  POWER  = GND
  D65  RSVD_D65  TRI  = NC
  D66  VSS_D66  POWER  = GND
  D67  VSS_D67  POWER  = GND
  D68  CORETYPE2  OUT  = CPU1_CORETYPE2
  D69  \pwrok||svi_rst_l\  OUT  = PWRGD_CPU1_PWROK
  D70  VSS_D70  POWER  = GND
  D71  VSS_D71  POWER  = GND
  D72  RSVD_D72  TRI  = NC
  D73  VSS_D73  POWER  = GND
  D74  VSS_D74  POWER  = GND
  DA1  VSS_DA1  POWER  = GND
  DA2  MGB_DATA26  BI  = M_G_CPU1_SB_DQ<26>
  DA3  MGB_DATA25  BI  = M_G_CPU1_SB_DQ<25>
  DA4  VSS_DA4  POWER  = GND
  DA5  MKB_DATA26  BI  = M_K_CPU1_SB_DQ<26>
  DA6  VSS_DA6  POWER  = GND
  DA7  MKB_DATA25  BI  = M_K_CPU1_SB_DQ<25>
  DA8  VSS_DA8  POWER  = GND
  DA9  MLB_DATA26  BI  = M_L_CPU1_SB_DQ<26>
  DA10  MLB_DATA25  BI  = M_L_CPU1_SB_DQ<25>
  DA11  VSS_DA11  POWER  = GND
  DA12  MHB_DATA26  BI  = M_H_CPU1_SB_DQ<26>
  DA13  VSS_DA13  POWER  = GND
  DA14  MHB_DATA25  BI  = M_H_CPU1_SB_DQ<25>
  DA15  VSS_DA15  POWER  = GND
  DA16  MJB_DATA26  BI  = M_J_CPU1_SB_DQ<26>
  DA17  MJB_DATA25  BI  = M_J_CPU1_SB_DQ<25>
  DA18  VSS_DA18  POWER  = GND
  DA19  MIB_DATA26  BI  = M_I_CPU1_SB_DQ<26>
  DA20  VSS_DA20  POWER  = GND
  DA21  MIB_DATA25  BI  = M_I_CPU1_SB_DQ<25>
  DA22  VSS_DA22  POWER  = GND
  DA23  P3_RXP14  IN  = P5E_CPU1_P3_RX_DP<14>
  DA24  P3_RXN14  IN  = P5E_CPU1_P3_RX_DN<14>
  DA25  VSS_DA25  POWER  = GND
  DA26  P3_RXP11  IN  = P5E_CPU1_P3_RX_DP<11>
  DA27  P3_RXN11  IN  = P5E_CPU1_P3_RX_DN<11>
  DA28  VSS_DA28  POWER  = GND
  DA29  P3_RXP8  IN  = P5E_CPU1_P3_RX_DP<8>
  DA30  P3_RXN8  IN  = P5E_CPU1_P3_RX_DN<8>
  DA31  VSS_DA31  POWER  = GND
  DA32  P3_RXP5  IN  = P5E_CPU1_P3_RX_DP<5>
  DA33  P3_RXN5  IN  = P5E_CPU1_P3_RX_DN<5>
  DA34  VSS_DA34  POWER  = GND
  DA35  VDDCR_CPU1_DA35  POWER  = PVDDCR_CPU1_P1
  DA36  VDDCR_CPU1_DA36  POWER  = PVDDCR_CPU1_P1
  DA40  VDDCR_CPU1_DA40  POWER  = PVDDCR_CPU1_P1
  DA41  VDDCR_CPU1_DA41  POWER  = PVDDCR_CPU1_P1
  DA42  VSS_DA42  POWER  = GND
  DA43  P1_TXN10  OUT  = P5E_CPU1_P1_TX_DN<10>
  DA44  P1_TXP10  OUT  = P5E_CPU1_P1_TX_DP<10>
  DA45  VSS_DA45  POWER  = GND
  DA46  P1_TXN7  OUT  = P5E_CPU1_P1_TX_DN<7>
  DA47  P1_TXP7  OUT  = P5E_CPU1_P1_TX_DP<7>
  DA48  VSS_DA48  POWER  = GND
  DA49  P1_TXN4  OUT  = P5E_CPU1_P1_TX_DN<4>
  DA50  P1_TXP4  OUT  = P5E_CPU1_P1_TX_DP<4>
  DA51  VSS_DA51  POWER  = GND
  DA52  P1_TXN1  OUT  = P5E_CPU1_P1_TX_DN<1>
  DA53  P1_TXP1  OUT  = P5E_CPU1_P1_TX_DP<1>
  DA54  VSS_DA54  POWER  = GND
  DA55  MCB_DATA25  BI  = M_C_CPU1_SB_DQ<25>
  DA56  VSS_DA56  POWER  = GND
  DA57  MCB_DATA26  BI  = M_C_CPU1_SB_DQ<26>
